# T6G (Grand Teton) — schematic netlist excerpt (pin names and nets, part order shuffled) for the footprints in the layout excerpt that follows; sources: Cadence DE-HDL packaged netlist, KiCad conversion of 04192023_DAF0TMB3IC0_F0TG_MB_C_brd_V02_OCP.brd

R2909  Q_RES  4.7K 5% CHIP  pkg 0402LF  page 130 : A = P3V3_AUX ; B = RST_SWB_BIC_R_N
PR6540  Q_RES  0 5% CHIP  pkg 0402LF  page 364 : A = NC_P0V9_RETIMER_CPU1_IMON4 ; B = GND

(kicad_pcb
	(version 20260206)
	(generator "pcbnew")
	(generator_version "10.0")
	(general
		(thickness 1.6)
		(legacy_teardrops no)
	)
	(paper "A4")
	(title_block
		(title "04192023_DAF0TMB3IC0_F0TG_MB_C_brd_V02_OCP.brd")
		(comment 1 "Grand Teton / footprints 6827-6828 of 8354")
	)
	(layers
		(0 "F.Cu" signal "TOP")
		(4 "In1.Cu" signal "GND")
		(6 "In2.Cu" signal "IN1")
		(8 "In3.Cu" signal "GND1")
		(10 "In4.Cu" signal "IN2")
		(12 "In5.Cu" signal "GND2")
		(14 "In6.Cu" signal "IN3")
		(16 "In7.Cu" signal "GND3")
		(18 "In8.Cu" signal "VCC")
		(20 "In9.Cu" signal "VCC1")
		(22 "In10.Cu" signal "GND4")
		(24 "In11.Cu" signal "IN4")
		(26 "In12.Cu" signal "GND5")
		(28 "In13.Cu" signal "IN5")
		(30 "In14.Cu" signal "GND6")
		(32 "In15.Cu" signal "IN6")
		(34 "In16.Cu" signal "GND7")
		(2 "B.Cu" signal "BOTTOM")
		(9 "F.Adhes" user "F.Adhesive")
		(11 "B.Adhes" user "B.Adhesive")
		(13 "F.Paste" user "Package Geometry/Pastemask Top")
		(15 "B.Paste" user "Package Geometry/Pastemask Bottom")
		(5 "F.SilkS" user "Ref Des/Silkscreen Top")
		(7 "B.SilkS" user "Ref Des/Silkscreen Bottom")
		(1 "F.Mask" user "Board Geometry/Soldermask Top")
		(3 "B.Mask" user "Board Geometry/Soldermask Bottom")
		(17 "Dwgs.User" user "User.Drawings")
		(19 "Cmts.User" user "User.Comments")
		(21 "Eco1.User" user "User.Eco1")
		(23 "Eco2.User" user "User.Eco2")
		(25 "Edge.Cuts" user "Board Geometry/Outline")
		(27 "Margin" user)
		(31 "F.CrtYd" user "Package Geometry/Place Bound Top")
		(29 "B.CrtYd" user "Package Geometry/Place Bound Bottom")
		(35 "F.Fab" user "Ref Des/Assembly Top")
		(33 "B.Fab" user "Ref Des/Assembly Bottom")
	)
	(footprint ""
		(layer "B.Cu")
		(at 172.456094 -415.808668 180)
		(property "Reference" "R2909"
			(at 0 0 0)
			(layer "B.SilkS")
			(hide yes)
			(effects
				(font
					(size 1.27 1.27)
				)
				(justify mirror)
			)
		)
		(property "Value" ""
			(at 0 0 0)
			(layer "B.Fab")
			(effects
				(font
					(size 1.27 1.27)
				)
				(justify mirror)
			)
		)
		(duplicate_pad_numbers_are_jumpers no)
		(fp_line
			(start 0.7874 0.4064)
			(end 0.7874 -0.4064)
			(stroke
				(width 0.1524)
				(type default)
			)
			(layer "B.SilkS")
		)
		(fp_line
			(start 0.7874 -0.4064)
			(end -0.7874 -0.4064)
			(stroke
				(width 0.1524)
				(type default)
			)
			(layer "B.SilkS")
		)
		(fp_line
			(start -0.7874 0.4064)
			(end 0.7874 0.4064)
			(stroke
				(width 0.1524)
				(type default)
			)
			(layer "B.SilkS")
		)
		(fp_line
			(start -0.7874 -0.4064)
			(end -0.7874 0.4064)
			(stroke
				(width 0.1524)
				(type default)
			)
			(layer "B.SilkS")
		)
		(fp_line
			(start 0.67945 0.3048)
			(end 0.67945 -0.305054)
			(stroke
				(width 0.1)
				(type default)
			)
			(layer "B.Fab")
		)
		(fp_line
			(start 0.67945 -0.305054)
			(end 0.12065 -0.305054)
			(stroke
				(width 0.1)
				(type default)
			)
			(layer "B.Fab")
		)
		(fp_line
			(start 0.12065 0.3048)
			(end 0.67945 0.3048)
			(stroke
				(width 0.1)
				(type default)
			)
			(layer "B.Fab")
		)
		(fp_line
			(start 0.12065 0.2794)
			(end 0.12065 0.3048)
			(stroke
				(width 0.1)
				(type default)
			)
			(layer "B.Fab")
		)
		(fp_line
			(start 0.12065 -0.2794)
			(end -0.12065 -0.2794)
			(stroke
				(width 0.1)
				(type default)
			)
			(layer "B.Fab")
		)
		(fp_line
			(start 0.12065 -0.305054)
			(end 0.12065 -0.2794)
			(stroke
				(width 0.1)
				(type default)
			)
			(layer "B.Fab")
		)
		(fp_line
			(start -0.120396 0.3048)
			(end -0.120396 0.2794)
			(stroke
				(width 0.1)
				(type default)
			)
			(layer "B.Fab")
		)
		(fp_line
			(start -0.120396 0.2794)
			(end 0.12065 0.2794)
			(stroke
				(width 0.1)
				(type default)
			)
			(layer "B.Fab")
		)
		(fp_line
			(start -0.12065 -0.2794)
			(end -0.12065 -0.3048)
			(stroke
				(width 0.1)
				(type default)
			)
			(layer "B.Fab")
		)
		(fp_line
			(start -0.12065 -0.3048)
			(end -0.67945 -0.3048)
			(stroke
				(width 0.1)
				(type default)
			)
			(layer "B.Fab")
		)
		(fp_line
			(start -0.67945 0.3048)
			(end -0.120396 0.3048)
			(stroke
				(width 0.1)
				(type default)
			)
			(layer "B.Fab")
		)
		(fp_line
			(start -0.67945 -0.3048)
			(end -0.67945 0.3048)
			(stroke
				(width 0.1)
				(type default)
			)
			(layer "B.Fab")
		)
		(pad "1" smd circle
			(at 0.40005 0)
			(size 0 0)
			(layers "B.Cu" "B.Mask" "B.Paste")
			(net "P3V3_AUX")
		)
		(pad "2" smd circle
			(at -0.40005 0)
			(size 0 0)
			(layers "B.Cu" "B.Mask" "B.Paste")
			(net "RST_SWB_BIC_R_N")
		)
	)
	(footprint ""
		(layer "B.Cu")
		(at 14.892782 -415.644584 -90)
		(property "Reference" "PR6540"
			(at 0 0 90)
			(layer "B.SilkS")
			(hide yes)
			(effects
				(font
					(size 1.27 1.27)
				)
				(justify mirror)
			)
		)
		(property "Value" ""
			(at 0 0 90)
			(layer "B.Fab")
			(effects
				(font
					(size 1.27 1.27)
				)
				(justify mirror)
			)
		)
		(duplicate_pad_numbers_are_jumpers no)
		(fp_line
			(start -0.7874 0.4064)
			(end 0.7874 0.4064)
			(stroke
				(width 0.1524)
				(type default)
			)
			(layer "B.SilkS")
		)
		(fp_line
			(start 0.7874 0.4064)
			(end 0.7874 -0.4064)
			(stroke
				(width 0.1524)
				(type default)
			)
			(layer "B.SilkS")
		)
		(fp_line
			(start -0.7874 -0.4064)
			(end -0.7874 0.4064)
			(stroke
				(width 0.1524)
				(type default)
			)
			(layer "B.SilkS")
		)
		(fp_line
			(start 0.7874 -0.4064)
			(end -0.7874 -0.4064)
			(stroke
				(width 0.1524)
				(type default)
			)
			(layer "B.SilkS")
		)
		(fp_line
			(start -0.67945 0.3048)
			(end -0.120396 0.3048)
			(stroke
				(width 0.1)
				(type default)
			)
			(layer "B.Fab")
		)
		(fp_line
			(start -0.120396 0.3048)
			(end -0.120396 0.2794)
			(stroke
				(width 0.1)
				(type default)
			)
			(layer "B.Fab")
		)
		(fp_line
			(start 0.12065 0.3048)
			(end 0.67945 0.3048)
			(stroke
				(width 0.1)
				(type default)
			)
			(layer "B.Fab")
		)
		(fp_line
			(start 0.67945 0.3048)
			(end 0.67945 -0.305054)
			(stroke
				(width 0.1)
				(type default)
			)
			(layer "B.Fab")
		)
		(fp_line
			(start -0.120396 0.2794)
			(end 0.12065 0.2794)
			(stroke
				(width 0.1)
				(type default)
			)
			(layer "B.Fab")
		)
		(fp_line
			(start 0.12065 0.2794)
			(end 0.12065 0.3048)
			(stroke
				(width 0.1)
				(type default)
			)
			(layer "B.Fab")
		)
		(fp_line
			(start -0.12065 -0.2794)
			(end -0.12065 -0.3048)
			(stroke
				(width 0.1)
				(type default)
			)
			(layer "B.Fab")
		)
		(fp_line
			(start 0.12065 -0.2794)
			(end -0.12065 -0.2794)
			(stroke
				(width 0.1)
				(type default)
			)
			(layer "B.Fab")
		)
		(fp_line
			(start -0.67945 -0.3048)
			(end -0.67945 0.3048)
			(stroke
				(width 0.1)
				(type default)
			)
			(layer "B.Fab")
		)
		(fp_line
			(start -0.12065 -0.3048)
			(end -0.67945 -0.3048)
			(stroke
				(width 0.1)
				(type default)
			)
			(layer "B.Fab")
		)
		(fp_line
			(start 0.12065 -0.305054)
			(end 0.12065 -0.2794)
			(stroke
				(width 0.1)
				(type default)
			)
			(layer "B.Fab")
		)
		(fp_line
			(start 0.67945 -0.305054)
			(end 0.12065 -0.305054)
			(stroke
				(width 0.1)
				(type default)
			)
			(layer "B.Fab")
		)
		(pad "1" smd circle
			(at 0.40005 0 90)
			(size 0 0)
			(layers "B.Cu" "B.Mask" "B.Paste")
			(net "NC_P0V9_RETIMER_CPU1_IMON4")
		)
		(pad "2" smd circle
			(at -0.40005 0 90)
			(size 0 0)
			(layers "B.Cu" "B.Mask" "B.Paste")
			(net "GND")
		)
	)
)
